(kicad_pcb
	(version 20260206)
	(generator "pcbnew")
	(generator_version "10.0")
	(general
		(thickness 1.6)
		(legacy_teardrops no)
	)
	(paper "A4")
	(title_block
		(title "Wiwynn_Tioga_Pass_MB.brd")
		(comment 1 "Tioga Pass / footprints 3616-3622 of 4770")
	)
	(layers
		(0 "F.Cu" signal "TOP")
		(4 "In1.Cu" signal "L2GND")
		(6 "In2.Cu" signal "L3")
		(8 "In3.Cu" signal "L4GND")
		(10 "In4.Cu" signal "L5")
		(12 "In5.Cu" signal "L6GND")
		(14 "In6.Cu" signal "L7VCC")
		(16 "In7.Cu" signal "L8VCC")
		(18 "In8.Cu" signal "L9GND")
		(20 "In9.Cu" signal "L10")
		(22 "In10.Cu" signal "L11GND")
		(24 "In11.Cu" signal "L12")
		(26 "In12.Cu" signal "L13GND")
		(2 "B.Cu" signal "BOTTOM")
		(9 "F.Adhes" user "F.Adhesive")
		(11 "B.Adhes" user "B.Adhesive")
		(13 "F.Paste" user "Package Geometry/Pastemask Top")
		(15 "B.Paste" user "Package Geometry/Pastemask Bottom")
		(5 "F.SilkS" user "Ref Des/Silkscreen Top")
		(7 "B.SilkS" user "Ref Des/Silkscreen Bottom")
		(1 "F.Mask" user "Board Geometry/Soldermask Top")
		(3 "B.Mask" user "Board Geometry/Soldermask Bottom")
		(17 "Dwgs.User" user "User.Drawings")
		(19 "Cmts.User" user "User.Comments")
		(21 "Eco1.User" user "User.Eco1")
		(23 "Eco2.User" user "User.Eco2")
		(25 "Edge.Cuts" user "Board Geometry/Outline")
		(27 "Margin" user)
		(31 "F.CrtYd" user "Package Geometry/Place Bound Top")
		(29 "B.CrtYd" user "Package Geometry/Place Bound Bottom")
		(35 "F.Fab" user "Ref Des/Assembly Top")
		(33 "B.Fab" user "Ref Des/Assembly Bottom")
	)
	(footprint ""
		(layer "B.Cu")
		(at 381.49022 -79.12354 -90)
		(property "Reference" "R9F55"
			(at 0 0 90)
			(layer "B.SilkS")
			(hide yes)
			(effects
				(font
					(size 1.27 1.27)
				)
				(justify mirror)
			)
		)
		(property "Value" ""
			(at 0 0 90)
			(layer "B.Fab")
			(effects
				(font
					(size 1.27 1.27)
				)
				(justify mirror)
			)
		)
		(duplicate_pad_numbers_are_jumpers no)
		(fp_poly
			(pts
				(xy 0.2794 -0.1016) (xy -0.2794 -0.1016) (xy -0.2794 0.9906) (xy 0.2794 0.9906)
			)
			(stroke
				(width 0)
				(type default)
			)
			(fill no)
			(layer "B.CrtYd")
		)
		(fp_line
			(start -0.2794 0.9906)
			(end -0.2794 -0.1016)
			(stroke
				(width 0.1)
				(type default)
			)
			(layer "B.Fab")
		)
		(fp_line
			(start 0.2794 0.9906)
			(end -0.2794 0.9906)
			(stroke
				(width 0.1)
				(type default)
			)
			(layer "B.Fab")
		)
		(fp_line
			(start -0.2794 -0.1016)
			(end 0.2794 -0.1016)
			(stroke
				(width 0.1)
				(type default)
			)
			(layer "B.Fab")
		)
		(fp_line
			(start 0.2794 -0.1016)
			(end 0.2794 0.9906)
			(stroke
				(width 0.1)
				(type default)
			)
			(layer "B.Fab")
		)
		(pad "1" smd rect
			(at 0 0 90)
			(size 0.508 0.508)
			(layers "B.Cu" "B.Mask" "B.Paste")
			(net "P3V3_STBY")
		)
		(pad "2" smd rect
			(at 0 0.889 90)
			(size 0.508 0.508)
			(layers "B.Cu" "B.Mask" "B.Paste")
			(net "FM_UART_ALERT_N")
		)
		(zone
			(layer "B.Cu")
			(hatch none 0.5)
			(connect_pads
				(clearance 0)
			)
			(min_thickness 0.25)
			(keepout
				(tracks not_allowed)
				(vias allowed)
				(pads allowed)
				(copperpour not_allowed)
				(footprints allowed)
			)
			(placement
				(enabled no)
				(sheetname "")
			)
			(fill
				(thermal_gap 0.5)
				(thermal_bridge_width 0.5)
				(island_removal_mode 0)
			)
			(polygon
				(pts
					(xy 380.85522 -78.86954) (xy 380.85522 -79.37754) (xy 381.23622 -79.37754) (xy 381.23622 -78.86954)
				)
			)
		)
		(zone
			(layer "B.Cu")
			(hatch none 0.5)
			(connect_pads
				(clearance 0)
			)
			(min_thickness 0.25)
			(keepout
				(tracks allowed)
				(vias not_allowed)
				(pads allowed)
				(copperpour not_allowed)
				(footprints allowed)
			)
			(placement
				(enabled no)
				(sheetname "")
			)
			(fill
				(thermal_gap 0.5)
				(thermal_bridge_width 0.5)
				(island_removal_mode 0)
			)
			(polygon
				(pts
					(xy 381.23622 -78.86954) (xy 381.23622 -79.37754) (xy 380.85522 -79.37754) (xy 380.85522 -78.86954)
				)
			)
		)
	)
	(footprint ""
		(layer "B.Cu")
		(at 382.3335 -44.958 90)
		(property "Reference" "R7E11"
			(at 0 0 90)
			(layer "B.SilkS")
			(hide yes)
			(effects
				(font
					(size 1.27 1.27)
				)
				(justify mirror)
			)
		)
		(property "Value" ""
			(at 0 0 90)
			(layer "B.Fab")
			(effects
				(font
					(size 1.27 1.27)
				)
				(justify mirror)
			)
		)
		(duplicate_pad_numbers_are_jumpers no)
		(fp_poly
			(pts
				(xy 0.2794 -0.1016) (xy -0.2794 -0.1016) (xy -0.2794 0.9906) (xy 0.2794 0.9906)
			)
			(stroke
				(width 0)
				(type default)
			)
			(fill no)
			(layer "B.CrtYd")
		)
		(fp_line
			(start 0.2794 -0.1016)
			(end 0.2794 0.9906)
			(stroke
				(width 0.1)
				(type default)
			)
			(layer "B.Fab")
		)
		(fp_line
			(start -0.2794 -0.1016)
			(end 0.2794 -0.1016)
			(stroke
				(width 0.1)
				(type default)
			)
			(layer "B.Fab")
		)
		(fp_line
			(start 0.2794 0.9906)
			(end -0.2794 0.9906)
			(stroke
				(width 0.1)
				(type default)
			)
			(layer "B.Fab")
		)
		(fp_line
			(start -0.2794 0.9906)
			(end -0.2794 -0.1016)
			(stroke
				(width 0.1)
				(type default)
			)
			(layer "B.Fab")
		)
		(pad "1" smd rect
			(at 0 0 270)
			(size 0.508 0.508)
			(layers "B.Cu" "B.Mask" "B.Paste")
			(net "P3V3")
		)
		(pad "2" smd rect
			(at 0 0.889 270)
			(size 0.508 0.508)
			(layers "B.Cu" "B.Mask" "B.Paste")
			(net "IRQ_CPU1_VRHOT")
		)
		(zone
			(layer "B.Cu")
			(hatch none 0.5)
			(connect_pads
				(clearance 0)
			)
			(min_thickness 0.25)
			(keepout
				(tracks allowed)
				(vias not_allowed)
				(pads allowed)
				(copperpour not_allowed)
				(footprints allowed)
			)
			(placement
				(enabled no)
				(sheetname "")
			)
			(fill
				(thermal_gap 0.5)
				(thermal_bridge_width 0.5)
				(island_removal_mode 0)
			)
			(polygon
				(pts
					(xy 382.5875 -45.212) (xy 382.5875 -44.704) (xy 382.9685 -44.704) (xy 382.9685 -45.212)
				)
			)
		)
		(zone
			(layer "B.Cu")
			(hatch none 0.5)
			(connect_pads
				(clearance 0)
			)
			(min_thickness 0.25)
			(keepout
				(tracks not_allowed)
				(vias allowed)
				(pads allowed)
				(copperpour not_allowed)
				(footprints allowed)
			)
			(placement
				(enabled no)
				(sheetname "")
			)
			(fill
				(thermal_gap 0.5)
				(thermal_bridge_width 0.5)
				(island_removal_mode 0)
			)
			(polygon
				(pts
					(xy 382.9685 -45.212) (xy 382.9685 -44.704) (xy 382.5875 -44.704) (xy 382.5875 -45.212)
				)
			)
		)
	)
	(footprint ""
		(layer "B.Cu")
		(at 3.920998 -16.934942 90)
		(property "Reference" "C9T9"
			(at 0 0 90)
			(layer "B.SilkS")
			(hide yes)
			(effects
				(font
					(size 1.27 1.27)
				)
				(justify mirror)
			)
		)
		(property "Value" ""
			(at 0 0 90)
			(layer "B.Fab")
			(effects
				(font
					(size 1.27 1.27)
				)
				(justify mirror)
			)
		)
		(duplicate_pad_numbers_are_jumpers no)
		(fp_rect
			(start -0.7239 -0.2159)
			(end 0.7239 1.9939)
			(stroke
				(width 0)
				(type default)
			)
			(fill no)
			(layer "B.CrtYd")
		)
		(fp_line
			(start 0.7239 -0.2159)
			(end 0.7239 1.9939)
			(stroke
				(width 0.1)
				(type default)
			)
			(layer "B.Fab")
		)
		(fp_line
			(start -0.7239 -0.2159)
			(end 0.7239 -0.2159)
			(stroke
				(width 0.1)
				(type default)
			)
			(layer "B.Fab")
		)
		(fp_line
			(start 0.7239 1.9939)
			(end -0.7239 1.9939)
			(stroke
				(width 0.1)
				(type default)
			)
			(layer "B.Fab")
		)
		(fp_line
			(start -0.7239 1.9939)
			(end -0.7239 -0.2159)
			(stroke
				(width 0.1)
				(type default)
			)
			(layer "B.Fab")
		)
		(pad "1" smd rect
			(at 0 0 270)
			(size 1.27 1.016)
			(layers "B.Cu" "B.Mask" "B.Paste")
			(net "VR_FET_SW_P12V_STBY_PVDDQ_GHJ")
		)
		(pad "2" smd rect
			(at 0 1.778 270)
			(size 1.27 1.016)
			(layers "B.Cu" "B.Mask" "B.Paste")
			(net "GND")
		)
		(zone
			(layer "B.Cu")
			(hatch none 0.5)
			(connect_pads
				(clearance 0)
			)
			(min_thickness 0.25)
			(keepout
				(tracks not_allowed)
				(vias allowed)
				(pads allowed)
				(copperpour not_allowed)
				(footprints allowed)
			)
			(placement
				(enabled no)
				(sheetname "")
			)
			(fill
				(thermal_gap 0.5)
				(thermal_bridge_width 0.5)
				(island_removal_mode 0)
			)
			(polygon
				(pts
					(xy 4.428998 -16.299942) (xy 5.190998 -16.299942) (xy 5.190998 -17.569942) (xy 4.428998 -17.569942)
				)
			)
		)
	)
	(footprint ""
		(layer "B.Cu")
		(at 173.863 -84.582 -90)
		(property "Reference" "C6P6"
			(at 0 0 90)
			(layer "B.SilkS")
			(hide yes)
			(effects
				(font
					(size 1.27 1.27)
				)
				(justify mirror)
			)
		)
		(property "Value" ""
			(at 0 0 90)
			(layer "B.Fab")
			(effects
				(font
					(size 1.27 1.27)
				)
				(justify mirror)
			)
		)
		(duplicate_pad_numbers_are_jumpers no)
		(fp_poly
			(pts
				(xy -0.3048 -0.1016) (xy -0.3048 0.9906) (xy 0.3048 0.9906) (xy 0.3048 -0.1016)
			)
			(stroke
				(width 0)
				(type default)
			)
			(fill no)
			(layer "B.CrtYd")
		)
		(fp_line
			(start -0.3048 0.9906)
			(end -0.3048 -0.1016)
			(stroke
				(width 0.1)
				(type default)
			)
			(layer "B.Fab")
		)
		(fp_line
			(start 0.3048 0.9906)
			(end -0.3048 0.9906)
			(stroke
				(width 0.1)
				(type default)
			)
			(layer "B.Fab")
		)
		(fp_line
			(start -0.3048 -0.1016)
			(end 0.3048 -0.1016)
			(stroke
				(width 0.1)
				(type default)
			)
			(layer "B.Fab")
		)
		(fp_line
			(start 0.3048 -0.1016)
			(end 0.3048 0.9906)
			(stroke
				(width 0.1)
				(type default)
			)
			(layer "B.Fab")
		)
		(pad "1" smd rect
			(at 0 0 90)
			(size 0.508 0.508)
			(layers "B.Cu" "B.Mask" "B.Paste")
			(net "P3V3_DB1200")
		)
		(pad "2" smd rect
			(at 0 0.889 90)
			(size 0.508 0.508)
			(layers "B.Cu" "B.Mask" "B.Paste")
			(net "GND")
		)
		(zone
			(layer "B.Cu")
			(hatch none 0.5)
			(connect_pads
				(clearance 0)
			)
			(min_thickness 0.25)
			(keepout
				(tracks not_allowed)
				(vias allowed)
				(pads allowed)
				(copperpour not_allowed)
				(footprints allowed)
			)
			(placement
				(enabled no)
				(sheetname "")
			)
			(fill
				(thermal_gap 0.5)
				(thermal_bridge_width 0.5)
				(island_removal_mode 0)
			)
			(polygon
				(pts
					(xy 173.228 -84.328) (xy 173.228 -84.836) (xy 173.609 -84.836) (xy 173.609 -84.328)
				)
			)
		)
		(zone
			(layer "B.Cu")
			(hatch none 0.5)
			(connect_pads
				(clearance 0)
			)
			(min_thickness 0.25)
			(keepout
				(tracks allowed)
				(vias not_allowed)
				(pads allowed)
				(copperpour not_allowed)
				(footprints allowed)
			)
			(placement
				(enabled no)
				(sheetname "")
			)
			(fill
				(thermal_gap 0.5)
				(thermal_bridge_width 0.5)
				(island_removal_mode 0)
			)
			(polygon
				(pts
					(xy 173.609 -84.328) (xy 173.609 -84.836) (xy 173.228 -84.836) (xy 173.228 -84.328)
				)
			)
		)
	)
	(footprint ""
		(layer "B.Cu")
		(at 388.64794 -84.75472 -90)
		(property "Reference" "R7D1"
			(at 0.8382 -0.67818 270)
			(unlocked yes)
			(layer "B.SilkS")
			(effects
				(font
					(size 0.4064 0.254)
					(thickness 0.1524)
				)
				(justify left mirror)
			)
		)
		(property "Value" ""
			(at 0 0 90)
			(layer "B.Fab")
			(effects
				(font
					(size 1.27 1.27)
				)
				(justify mirror)
			)
		)
		(duplicate_pad_numbers_are_jumpers no)
		(fp_poly
			(pts
				(xy 0.2794 -0.1016) (xy -0.2794 -0.1016) (xy -0.2794 0.9906) (xy 0.2794 0.9906)
			)
			(stroke
				(width 0)
				(type default)
			)
			(fill no)
			(layer "B.CrtYd")
		)
		(fp_line
			(start -0.2794 0.9906)
			(end -0.2794 -0.1016)
			(stroke
				(width 0.1)
				(type default)
			)
			(layer "B.Fab")
		)
		(fp_line
			(start 0.2794 0.9906)
			(end -0.2794 0.9906)
			(stroke
				(width 0.1)
				(type default)
			)
			(layer "B.Fab")
		)
		(fp_line
			(start -0.2794 -0.1016)
			(end 0.2794 -0.1016)
			(stroke
				(width 0.1)
				(type default)
			)
			(layer "B.Fab")
		)
		(fp_line
			(start 0.2794 -0.1016)
			(end 0.2794 0.9906)
			(stroke
				(width 0.1)
				(type default)
			)
			(layer "B.Fab")
		)
		(pad "1" smd rect
			(at 0 0 90)
			(size 0.508 0.508)
			(layers "B.Cu" "B.Mask" "B.Paste")
			(net "RMII_PCH_SPRNGVLLE_ARB_OUT")
		)
		(pad "2" smd rect
			(at 0 0.889 90)
			(size 0.508 0.508)
			(layers "B.Cu" "B.Mask" "B.Paste")
			(net "GND")
		)
		(zone
			(layer "B.Cu")
			(hatch none 0.5)
			(connect_pads
				(clearance 0)
			)
			(min_thickness 0.25)
			(keepout
				(tracks not_allowed)
				(vias allowed)
				(pads allowed)
				(copperpour not_allowed)
				(footprints allowed)
			)
			(placement
				(enabled no)
				(sheetname "")
			)
			(fill
				(thermal_gap 0.5)
				(thermal_bridge_width 0.5)
				(island_removal_mode 0)
			)
			(polygon
				(pts
					(xy 388.01294 -84.50072) (xy 388.01294 -85.00872) (xy 388.39394 -85.00872) (xy 388.39394 -84.50072)
				)
			)
		)
		(zone
			(layer "B.Cu")
			(hatch none 0.5)
			(connect_pads
				(clearance 0)
			)
			(min_thickness 0.25)
			(keepout
				(tracks allowed)
				(vias not_allowed)
				(pads allowed)
				(copperpour not_allowed)
				(footprints allowed)
			)
			(placement
				(enabled no)
				(sheetname "")
			)
			(fill
				(thermal_gap 0.5)
				(thermal_bridge_width 0.5)
				(island_removal_mode 0)
			)
			(polygon
				(pts
					(xy 388.39394 -84.50072) (xy 388.39394 -85.00872) (xy 388.01294 -85.00872) (xy 388.01294 -84.50072)
				)
			)
		)
	)
	(footprint ""
		(layer "B.Cu")
		(at 177.927 -79.121)
		(property "Reference" "R6P48"
			(at 0 0 0)
			(layer "B.SilkS")
			(hide yes)
			(effects
				(font
					(size 1.27 1.27)
				)
				(justify mirror)
			)
		)
		(property "Value" ""
			(at 0 0 0)
			(layer "B.Fab")
			(effects
				(font
					(size 1.27 1.27)
				)
				(justify mirror)
			)
		)
		(duplicate_pad_numbers_are_jumpers no)
		(fp_poly
			(pts
				(xy 0.2794 -0.1016) (xy -0.2794 -0.1016) (xy -0.2794 0.9906) (xy 0.2794 0.9906)
			)
			(stroke
				(width 0)
				(type default)
			)
			(fill no)
			(layer "B.CrtYd")
		)
		(fp_line
			(start -0.2794 -0.1016)
			(end 0.2794 -0.1016)
			(stroke
				(width 0.1)
				(type default)
			)
			(layer "B.Fab")
		)
		(fp_line
			(start -0.2794 0.9906)
			(end -0.2794 -0.1016)
			(stroke
				(width 0.1)
				(type default)
			)
			(layer "B.Fab")
		)
		(fp_line
			(start 0.2794 -0.1016)
			(end 0.2794 0.9906)
			(stroke
				(width 0.1)
				(type default)
			)
			(layer "B.Fab")
		)
		(fp_line
			(start 0.2794 0.9906)
			(end -0.2794 0.9906)
			(stroke
				(width 0.1)
				(type default)
			)
			(layer "B.Fab")
		)
		(pad "1" smd rect
			(at 0 0 180)
			(size 0.508 0.508)
			(layers "B.Cu" "B.Mask" "B.Paste")
			(net "P3V3")
		)
		(pad "2" smd rect
			(at 0 0.889 180)
			(size 0.508 0.508)
			(layers "B.Cu" "B.Mask" "B.Paste")
			(net "FM_DB1200ZL_BCLKS_EN_N")
		)
		(zone
			(layer "B.Cu")
			(hatch none 0.5)
			(connect_pads
				(clearance 0)
			)
			(min_thickness 0.25)
			(keepout
				(tracks allowed)
				(vias not_allowed)
				(pads allowed)
				(copperpour not_allowed)
				(footprints allowed)
			)
			(placement
				(enabled no)
				(sheetname "")
			)
			(fill
				(thermal_gap 0.5)
				(thermal_bridge_width 0.5)
				(island_removal_mode 0)
			)
			(polygon
				(pts
					(xy 178.181 -78.867) (xy 177.673 -78.867) (xy 177.673 -78.486) (xy 178.181 -78.486)
				)
			)
		)
		(zone
			(layer "B.Cu")
			(hatch none 0.5)
			(connect_pads
				(clearance 0)
			)
			(min_thickness 0.25)
			(keepout
				(tracks not_allowed)
				(vias allowed)
				(pads allowed)
				(copperpour not_allowed)
				(footprints allowed)
			)
			(placement
				(enabled no)
				(sheetname "")
			)
			(fill
				(thermal_gap 0.5)
				(thermal_bridge_width 0.5)
				(island_removal_mode 0)
			)
			(polygon
				(pts
					(xy 178.181 -78.486) (xy 177.673 -78.486) (xy 177.673 -78.867) (xy 178.181 -78.867)
				)
			)
		)
	)
	(footprint ""
		(layer "B.Cu")
		(at 417.8173 -48.9204 90)
		(property "Reference" "R1T7"
			(at 0 0 90)
			(layer "B.SilkS")
			(hide yes)
			(effects
				(font
					(size 1.27 1.27)
				)
				(justify mirror)
			)
		)
		(property "Value" ""
			(at 0 0 90)
			(layer "B.Fab")
			(effects
				(font
					(size 1.27 1.27)
				)
				(justify mirror)
			)
		)
		(duplicate_pad_numbers_are_jumpers no)
		(fp_poly
			(pts
				(xy 0.2794 -0.1016) (xy -0.2794 -0.1016) (xy -0.2794 0.9906) (xy 0.2794 0.9906)
			)
			(stroke
				(width 0)
				(type default)
			)
			(fill no)
			(layer "B.CrtYd")
		)
		(fp_line
			(start 0.2794 -0.1016)
			(end 0.2794 0.9906)
			(stroke
				(width 0.1)
				(type default)
			)
			(layer "B.Fab")
		)
		(fp_line
			(start -0.2794 -0.1016)
			(end 0.2794 -0.1016)
			(stroke
				(width 0.1)
				(type default)
			)
			(layer "B.Fab")
		)
		(fp_line
			(start 0.2794 0.9906)
			(end -0.2794 0.9906)
			(stroke
				(width 0.1)
				(type default)
			)
			(layer "B.Fab")
		)
		(fp_line
			(start -0.2794 0.9906)
			(end -0.2794 -0.1016)
			(stroke
				(width 0.1)
				(type default)
			)
			(layer "B.Fab")
		)
		(pad "1" smd rect
			(at 0 0 270)
			(size 0.508 0.508)
			(layers "B.Cu" "B.Mask" "B.Paste")
			(net "SMB_SLOTX24_STBY_LVC3_SCL_R")
		)
		(pad "2" smd rect
			(at 0 0.889 270)
			(size 0.508 0.508)
			(layers "B.Cu" "B.Mask" "B.Paste")
			(net "SMB_SLOTX24_BMC_STBY_LVC3_SCL")
		)
		(zone
			(layer "B.Cu")
			(hatch none 0.5)
			(connect_pads
				(clearance 0)
			)
			(min_thickness 0.25)
			(keepout
				(tracks allowed)
				(vias not_allowed)
				(pads allowed)
				(copperpour not_allowed)
				(footprints allowed)
			)
			(placement
				(enabled no)
				(sheetname "")
			)
			(fill
				(thermal_gap 0.5)
				(thermal_bridge_width 0.5)
				(island_removal_mode 0)
			)
			(polygon
				(pts
					(xy 418.0713 -49.1744) (xy 418.0713 -48.6664) (xy 418.4523 -48.6664) (xy 418.4523 -49.1744)
				)
			)
		)
		(zone
			(layer "B.Cu")
			(hatch none 0.5)
			(connect_pads
				(clearance 0)
			)
			(min_thickness 0.25)
			(keepout
				(tracks not_allowed)
				(vias allowed)
				(pads allowed)
				(copperpour not_allowed)
				(footprints allowed)
			)
			(placement
				(enabled no)
				(sheetname "")
			)
			(fill
				(thermal_gap 0.5)
				(thermal_bridge_width 0.5)
				(island_removal_mode 0)
			)
			(polygon
				(pts
					(xy 418.4523 -49.1744) (xy 418.4523 -48.6664) (xy 418.0713 -48.6664) (xy 418.0713 -49.1744)
				)
			)
		)
	)
)
